(kicad_pcb
	(version 20260206)
	(generator "pcbnew")
	(generator_version "10.0")
	(general
		(thickness 1.6)
		(legacy_teardrops no)
	)
	(paper "A4")
	(title_block
		(title "Wiwynn_Tioga_Pass_MB.brd")
		(comment 1 "Tioga Pass / footprints 3721-3728 of 4770")
	)
	(layers
		(0 "F.Cu" signal "TOP")
		(4 "In1.Cu" signal "L2GND")
		(6 "In2.Cu" signal "L3")
		(8 "In3.Cu" signal "L4GND")
		(10 "In4.Cu" signal "L5")
		(12 "In5.Cu" signal "L6GND")
		(14 "In6.Cu" signal "L7VCC")
		(16 "In7.Cu" signal "L8VCC")
		(18 "In8.Cu" signal "L9GND")
		(20 "In9.Cu" signal "L10")
		(22 "In10.Cu" signal "L11GND")
		(24 "In11.Cu" signal "L12")
		(26 "In12.Cu" signal "L13GND")
		(2 "B.Cu" signal "BOTTOM")
		(9 "F.Adhes" user "F.Adhesive")
		(11 "B.Adhes" user "B.Adhesive")
		(13 "F.Paste" user "Package Geometry/Pastemask Top")
		(15 "B.Paste" user "Package Geometry/Pastemask Bottom")
		(5 "F.SilkS" user "Ref Des/Silkscreen Top")
		(7 "B.SilkS" user "Ref Des/Silkscreen Bottom")
		(1 "F.Mask" user "Board Geometry/Soldermask Top")
		(3 "B.Mask" user "Board Geometry/Soldermask Bottom")
		(17 "Dwgs.User" user "User.Drawings")
		(19 "Cmts.User" user "User.Comments")
		(21 "Eco1.User" user "User.Eco1")
		(23 "Eco2.User" user "User.Eco2")
		(25 "Edge.Cuts" user "Board Geometry/Outline")
		(27 "Margin" user)
		(31 "F.CrtYd" user "Package Geometry/Place Bound Top")
		(29 "B.CrtYd" user "Package Geometry/Place Bound Bottom")
		(35 "F.Fab" user "Ref Des/Assembly Top")
		(33 "B.Fab" user "Ref Des/Assembly Bottom")
	)
	(footprint ""
		(layer "B.Cu")
		(at 371.545358 -75.494388)
		(property "Reference" "C2P7"
			(at 0 0 0)
			(layer "B.SilkS")
			(hide yes)
			(effects
				(font
					(size 1.27 1.27)
				)
				(justify mirror)
			)
		)
		(property "Value" ""
			(at 0 0 0)
			(layer "B.Fab")
			(effects
				(font
					(size 1.27 1.27)
				)
				(justify mirror)
			)
		)
		(duplicate_pad_numbers_are_jumpers no)
		(fp_rect
			(start 0.2794 0.9144)
			(end -0.2794 -0.1143)
			(stroke
				(width 0)
				(type default)
			)
			(fill no)
			(layer "B.CrtYd")
		)
		(fp_line
			(start -0.2794 -0.1143)
			(end -0.2794 0.9144)
			(stroke
				(width 0.1)
				(type default)
			)
			(layer "B.Fab")
		)
		(fp_line
			(start -0.2794 0.9144)
			(end 0.2794 0.9144)
			(stroke
				(width 0.1)
				(type default)
			)
			(layer "B.Fab")
		)
		(fp_line
			(start 0.2794 -0.1143)
			(end -0.2794 -0.1143)
			(stroke
				(width 0.1)
				(type default)
			)
			(layer "B.Fab")
		)
		(fp_line
			(start 0.2794 0.9144)
			(end 0.2794 -0.1143)
			(stroke
				(width 0.1)
				(type default)
			)
			(layer "B.Fab")
		)
		(pad "1" smd custom
			(at 0 0 270)
			(size 0.10414 0.10414)
			(layers "B.Cu" "B.Mask" "B.Paste")
			(net "P3V3_STBY")
			(options
				(clearance outline)
				(anchor circle)
			)
			(primitives
				(gr_poly
					(pts
						(xy -0.20828 -0.08636) (xy -0.20828 0.08636) (xy -0.08636 0.20828) (xy 0.086614 0.20828) (xy 0.20828 0.086614)
						(xy 0.20828 -0.08636) (xy 0.08636 -0.20828) (xy -0.08636 -0.20828)
					)
					(width 0)
					(fill yes)
				)
			)
		)
		(pad "2" smd custom
			(at 0 0.8001 270)
			(size 0.10414 0.10414)
			(layers "B.Cu" "B.Mask" "B.Paste")
			(net "GND")
			(options
				(clearance outline)
				(anchor circle)
			)
			(primitives
				(gr_poly
					(pts
						(xy -0.20828 -0.08636) (xy -0.20828 0.08636) (xy -0.08636 0.20828) (xy 0.086614 0.20828) (xy 0.20828 0.086614)
						(xy 0.20828 -0.08636) (xy 0.08636 -0.20828) (xy -0.08636 -0.20828)
					)
					(width 0)
					(fill yes)
				)
			)
		)
		(zone
			(layer "B.Cu")
			(hatch none 0.5)
			(connect_pads
				(clearance 0)
			)
			(min_thickness 0.25)
			(keepout
				(tracks allowed)
				(vias not_allowed)
				(pads allowed)
				(copperpour not_allowed)
				(footprints allowed)
			)
			(placement
				(enabled no)
				(sheetname "")
			)
			(fill
				(thermal_gap 0.5)
				(thermal_bridge_width 0.5)
				(island_removal_mode 0)
			)
			(polygon
				(pts
					(xy 371.632988 -75.284838) (xy 371.632988 -74.903838) (xy 371.457728 -74.903838) (xy 371.457474 -75.284838)
				)
			)
		)
		(zone
			(layer "B.Cu")
			(hatch none 0.5)
			(connect_pads
				(clearance 0)
			)
			(min_thickness 0.25)
			(keepout
				(tracks not_allowed)
				(vias allowed)
				(pads allowed)
				(copperpour not_allowed)
				(footprints allowed)
			)
			(placement
				(enabled no)
				(sheetname "")
			)
			(fill
				(thermal_gap 0.5)
				(thermal_bridge_width 0.5)
				(island_removal_mode 0)
			)
			(polygon
				(pts
					(xy 371.632988 -75.284838) (xy 371.632988 -74.903838) (xy 371.457728 -74.903838) (xy 371.457474 -75.284838)
				)
			)
		)
	)
	(footprint ""
		(layer "B.Cu")
		(at 408.7622 -103.8098)
		(property "Reference" "C2N24"
			(at 0 0 0)
			(layer "B.SilkS")
			(hide yes)
			(effects
				(font
					(size 1.27 1.27)
				)
				(justify mirror)
			)
		)
		(property "Value" ""
			(at 0 0 0)
			(layer "B.Fab")
			(effects
				(font
					(size 1.27 1.27)
				)
				(justify mirror)
			)
		)
		(duplicate_pad_numbers_are_jumpers no)
		(fp_poly
			(pts
				(xy 0.4953 -0.2032) (xy -0.4953 -0.2032) (xy -0.4953 1.6002) (xy 0.4953 1.6002)
			)
			(stroke
				(width 0)
				(type default)
			)
			(fill no)
			(layer "B.CrtYd")
		)
		(fp_line
			(start -0.4953 -0.2032)
			(end -0.4953 1.6002)
			(stroke
				(width 0.1)
				(type default)
			)
			(layer "B.Fab")
		)
		(fp_line
			(start -0.4953 1.6002)
			(end 0.4953 1.6002)
			(stroke
				(width 0.1)
				(type default)
			)
			(layer "B.Fab")
		)
		(fp_line
			(start 0.4953 -0.2032)
			(end -0.4953 -0.2032)
			(stroke
				(width 0.1)
				(type default)
			)
			(layer "B.Fab")
		)
		(fp_line
			(start 0.4953 1.6002)
			(end 0.4953 -0.2032)
			(stroke
				(width 0.1)
				(type default)
			)
			(layer "B.Fab")
		)
		(pad "1" smd rect
			(at 0 0 180)
			(size 0.762 0.889)
			(layers "B.Cu" "B.Mask" "B.Paste")
			(net "P3V3_STBY")
		)
		(pad "2" smd rect
			(at 0 1.397 180)
			(size 0.762 0.889)
			(layers "B.Cu" "B.Mask" "B.Paste")
			(net "GND")
		)
		(zone
			(layer "B.Cu")
			(hatch none 0.5)
			(connect_pads
				(clearance 0)
			)
			(min_thickness 0.25)
			(keepout
				(tracks not_allowed)
				(vias allowed)
				(pads allowed)
				(copperpour not_allowed)
				(footprints allowed)
			)
			(placement
				(enabled no)
				(sheetname "")
			)
			(fill
				(thermal_gap 0.5)
				(thermal_bridge_width 0.5)
				(island_removal_mode 0)
			)
			(polygon
				(pts
					(xy 409.1432 -103.3653) (xy 408.3812 -103.3653) (xy 408.3812 -102.8573) (xy 409.1432 -102.8573)
				)
			)
		)
	)
	(footprint ""
		(layer "B.Cu")
		(at 386.969 -47.244 -90)
		(property "Reference" "R3T9"
			(at 0 0 90)
			(layer "B.SilkS")
			(hide yes)
			(effects
				(font
					(size 1.27 1.27)
				)
				(justify mirror)
			)
		)
		(property "Value" ""
			(at 0 0 90)
			(layer "B.Fab")
			(effects
				(font
					(size 1.27 1.27)
				)
				(justify mirror)
			)
		)
		(duplicate_pad_numbers_are_jumpers no)
		(fp_poly
			(pts
				(xy 0.2794 -0.1016) (xy -0.2794 -0.1016) (xy -0.2794 0.9906) (xy 0.2794 0.9906)
			)
			(stroke
				(width 0)
				(type default)
			)
			(fill no)
			(layer "B.CrtYd")
		)
		(fp_line
			(start -0.2794 0.9906)
			(end -0.2794 -0.1016)
			(stroke
				(width 0.1)
				(type default)
			)
			(layer "B.Fab")
		)
		(fp_line
			(start 0.2794 0.9906)
			(end -0.2794 0.9906)
			(stroke
				(width 0.1)
				(type default)
			)
			(layer "B.Fab")
		)
		(fp_line
			(start -0.2794 -0.1016)
			(end 0.2794 -0.1016)
			(stroke
				(width 0.1)
				(type default)
			)
			(layer "B.Fab")
		)
		(fp_line
			(start 0.2794 -0.1016)
			(end 0.2794 0.9906)
			(stroke
				(width 0.1)
				(type default)
			)
			(layer "B.Fab")
		)
		(pad "1" smd rect
			(at 0 0 90)
			(size 0.508 0.508)
			(layers "B.Cu" "B.Mask" "B.Paste")
			(net "PU_BIOS_SPI_WP1_N")
		)
		(pad "2" smd rect
			(at 0 0.889 90)
			(size 0.508 0.508)
			(layers "B.Cu" "B.Mask" "B.Paste")
			(net "GND")
		)
		(zone
			(layer "B.Cu")
			(hatch none 0.5)
			(connect_pads
				(clearance 0)
			)
			(min_thickness 0.25)
			(keepout
				(tracks not_allowed)
				(vias allowed)
				(pads allowed)
				(copperpour not_allowed)
				(footprints allowed)
			)
			(placement
				(enabled no)
				(sheetname "")
			)
			(fill
				(thermal_gap 0.5)
				(thermal_bridge_width 0.5)
				(island_removal_mode 0)
			)
			(polygon
				(pts
					(xy 386.334 -46.99) (xy 386.334 -47.498) (xy 386.715 -47.498) (xy 386.715 -46.99)
				)
			)
		)
		(zone
			(layer "B.Cu")
			(hatch none 0.5)
			(connect_pads
				(clearance 0)
			)
			(min_thickness 0.25)
			(keepout
				(tracks allowed)
				(vias not_allowed)
				(pads allowed)
				(copperpour not_allowed)
				(footprints allowed)
			)
			(placement
				(enabled no)
				(sheetname "")
			)
			(fill
				(thermal_gap 0.5)
				(thermal_bridge_width 0.5)
				(island_removal_mode 0)
			)
			(polygon
				(pts
					(xy 386.715 -46.99) (xy 386.715 -47.498) (xy 386.334 -47.498) (xy 386.334 -46.99)
				)
			)
		)
	)
	(footprint ""
		(layer "B.Cu")
		(at 95.377254 -77.82814)
		(property "Reference" "C8P20"
			(at 0 0 0)
			(layer "B.SilkS")
			(hide yes)
			(effects
				(font
					(size 1.27 1.27)
				)
				(justify mirror)
			)
		)
		(property "Value" ""
			(at 0 0 0)
			(layer "B.Fab")
			(effects
				(font
					(size 1.27 1.27)
				)
				(justify mirror)
			)
		)
		(duplicate_pad_numbers_are_jumpers no)
		(fp_poly
			(pts
				(xy 0.7239 -0.2159) (xy -0.7239 -0.2159) (xy -0.7239 1.9939) (xy 0.7239 1.9939)
			)
			(stroke
				(width 0)
				(type default)
			)
			(fill no)
			(layer "B.CrtYd")
		)
		(fp_line
			(start -0.7239 -0.2159)
			(end 0.7239 -0.2159)
			(stroke
				(width 0.1)
				(type default)
			)
			(layer "B.Fab")
		)
		(fp_line
			(start -0.7239 1.9939)
			(end -0.7239 -0.2159)
			(stroke
				(width 0.1)
				(type default)
			)
			(layer "B.Fab")
		)
		(fp_line
			(start 0.7239 -0.2159)
			(end 0.7239 1.9939)
			(stroke
				(width 0.1)
				(type default)
			)
			(layer "B.Fab")
		)
		(fp_line
			(start 0.7239 1.9939)
			(end -0.7239 1.9939)
			(stroke
				(width 0.1)
				(type default)
			)
			(layer "B.Fab")
		)
		(pad "1" smd rect
			(at 0 0 180)
			(size 1.27 1.016)
			(layers "B.Cu" "B.Mask" "B.Paste")
			(net "PVCCIN_CPU1")
		)
		(pad "2" smd rect
			(at 0 1.778 180)
			(size 1.27 1.016)
			(layers "B.Cu" "B.Mask" "B.Paste")
			(net "GND")
		)
		(zone
			(layer "B.Cu")
			(hatch none 0.5)
			(connect_pads
				(clearance 0)
			)
			(min_thickness 0.25)
			(keepout
				(tracks not_allowed)
				(vias allowed)
				(pads allowed)
				(copperpour not_allowed)
				(footprints allowed)
			)
			(placement
				(enabled no)
				(sheetname "")
			)
			(fill
				(thermal_gap 0.5)
				(thermal_bridge_width 0.5)
				(island_removal_mode 0)
			)
			(polygon
				(pts
					(xy 96.012254 -77.32014) (xy 94.742254 -77.32014) (xy 94.742254 -76.55814) (xy 96.012254 -76.55814)
				)
			)
		)
	)
	(footprint ""
		(layer "B.Cu")
		(at 479.8695 -40.4114 90)
		(property "Reference" "C1R26"
			(at 0 0 90)
			(layer "B.SilkS")
			(hide yes)
			(effects
				(font
					(size 1.27 1.27)
				)
				(justify mirror)
			)
		)
		(property "Value" ""
			(at 0 0 90)
			(layer "B.Fab")
			(effects
				(font
					(size 1.27 1.27)
				)
				(justify mirror)
			)
		)
		(duplicate_pad_numbers_are_jumpers no)
		(fp_poly
			(pts
				(xy -0.3048 -0.1016) (xy -0.3048 0.9906) (xy 0.3048 0.9906) (xy 0.3048 -0.1016)
			)
			(stroke
				(width 0)
				(type default)
			)
			(fill no)
			(layer "B.CrtYd")
		)
		(fp_line
			(start 0.3048 -0.1016)
			(end 0.3048 0.9906)
			(stroke
				(width 0.1)
				(type default)
			)
			(layer "B.Fab")
		)
		(fp_line
			(start -0.3048 -0.1016)
			(end 0.3048 -0.1016)
			(stroke
				(width 0.1)
				(type default)
			)
			(layer "B.Fab")
		)
		(fp_line
			(start 0.3048 0.9906)
			(end -0.3048 0.9906)
			(stroke
				(width 0.1)
				(type default)
			)
			(layer "B.Fab")
		)
		(fp_line
			(start -0.3048 0.9906)
			(end -0.3048 -0.1016)
			(stroke
				(width 0.1)
				(type default)
			)
			(layer "B.Fab")
		)
		(pad "1" smd rect
			(at 0 0 270)
			(size 0.508 0.508)
			(layers "B.Cu" "B.Mask" "B.Paste")
			(net "P1V5_LAN")
		)
		(pad "2" smd rect
			(at 0 0.889 270)
			(size 0.508 0.508)
			(layers "B.Cu" "B.Mask" "B.Paste")
			(net "GND")
		)
		(zone
			(layer "B.Cu")
			(hatch none 0.5)
			(connect_pads
				(clearance 0)
			)
			(min_thickness 0.25)
			(keepout
				(tracks allowed)
				(vias not_allowed)
				(pads allowed)
				(copperpour not_allowed)
				(footprints allowed)
			)
			(placement
				(enabled no)
				(sheetname "")
			)
			(fill
				(thermal_gap 0.5)
				(thermal_bridge_width 0.5)
				(island_removal_mode 0)
			)
			(polygon
				(pts
					(xy 480.1235 -40.6654) (xy 480.1235 -40.1574) (xy 480.5045 -40.1574) (xy 480.5045 -40.6654)
				)
			)
		)
		(zone
			(layer "B.Cu")
			(hatch none 0.5)
			(connect_pads
				(clearance 0)
			)
			(min_thickness 0.25)
			(keepout
				(tracks not_allowed)
				(vias allowed)
				(pads allowed)
				(copperpour not_allowed)
				(footprints allowed)
			)
			(placement
				(enabled no)
				(sheetname "")
			)
			(fill
				(thermal_gap 0.5)
				(thermal_bridge_width 0.5)
				(island_removal_mode 0)
			)
			(polygon
				(pts
					(xy 480.5045 -40.6654) (xy 480.5045 -40.1574) (xy 480.1235 -40.1574) (xy 480.1235 -40.6654)
				)
			)
		)
	)
	(footprint ""
		(layer "B.Cu")
		(at 485.6734 -39.7256 180)
		(property "Reference" "C1T4"
			(at 0 0 0)
			(layer "B.SilkS")
			(hide yes)
			(effects
				(font
					(size 1.27 1.27)
				)
				(justify mirror)
			)
		)
		(property "Value" ""
			(at 0 0 0)
			(layer "B.Fab")
			(effects
				(font
					(size 1.27 1.27)
				)
				(justify mirror)
			)
		)
		(duplicate_pad_numbers_are_jumpers no)
		(fp_poly
			(pts
				(xy 0.4953 -0.2032) (xy -0.4953 -0.2032) (xy -0.4953 1.6002) (xy 0.4953 1.6002)
			)
			(stroke
				(width 0)
				(type default)
			)
			(fill no)
			(layer "B.CrtYd")
		)
		(fp_line
			(start 0.4953 1.6002)
			(end 0.4953 -0.2032)
			(stroke
				(width 0.1)
				(type default)
			)
			(layer "B.Fab")
		)
		(fp_line
			(start 0.4953 -0.2032)
			(end -0.4953 -0.2032)
			(stroke
				(width 0.1)
				(type default)
			)
			(layer "B.Fab")
		)
		(fp_line
			(start -0.4953 1.6002)
			(end 0.4953 1.6002)
			(stroke
				(width 0.1)
				(type default)
			)
			(layer "B.Fab")
		)
		(fp_line
			(start -0.4953 -0.2032)
			(end -0.4953 1.6002)
			(stroke
				(width 0.1)
				(type default)
			)
			(layer "B.Fab")
		)
		(pad "1" smd rect
			(at 0 0)
			(size 0.762 0.889)
			(layers "B.Cu" "B.Mask" "B.Paste")
			(net "P0V9_LAN")
		)
		(pad "2" smd rect
			(at 0 1.397)
			(size 0.762 0.889)
			(layers "B.Cu" "B.Mask" "B.Paste")
			(net "GND")
		)
		(zone
			(layer "B.Cu")
			(hatch none 0.5)
			(connect_pads
				(clearance 0)
			)
			(min_thickness 0.25)
			(keepout
				(tracks not_allowed)
				(vias allowed)
				(pads allowed)
				(copperpour not_allowed)
				(footprints allowed)
			)
			(placement
				(enabled no)
				(sheetname "")
			)
			(fill
				(thermal_gap 0.5)
				(thermal_bridge_width 0.5)
				(island_removal_mode 0)
			)
			(polygon
				(pts
					(xy 485.2924 -40.1701) (xy 486.0544 -40.1701) (xy 486.0544 -40.6781) (xy 485.2924 -40.6781)
				)
			)
		)
	)
	(footprint ""
		(layer "B.Cu")
		(at 88.392 -149.8092 90)
		(property "Reference" "C5G98"
			(at -1.14681 0.76708 180)
			(unlocked yes)
			(layer "B.SilkS")
			(effects
				(font
					(size 0.7874 0.5842)
					(thickness 0.1524)
				)
				(justify mirror)
			)
		)
		(property "Value" ""
			(at 0 0 90)
			(layer "B.Fab")
			(effects
				(font
					(size 1.27 1.27)
				)
				(justify mirror)
			)
		)
		(duplicate_pad_numbers_are_jumpers no)
		(fp_rect
			(start -0.4953 -0.2032)
			(end 0.4953 1.6002)
			(stroke
				(width 0)
				(type default)
			)
			(fill no)
			(layer "B.CrtYd")
		)
		(fp_line
			(start 0.4953 -0.2032)
			(end -0.4953 -0.2032)
			(stroke
				(width 0.1)
				(type default)
			)
			(layer "B.Fab")
		)
		(fp_line
			(start -0.4953 -0.2032)
			(end -0.4953 1.6002)
			(stroke
				(width 0.1)
				(type default)
			)
			(layer "B.Fab")
		)
		(fp_line
			(start 0.4953 1.6002)
			(end 0.4953 -0.2032)
			(stroke
				(width 0.1)
				(type default)
			)
			(layer "B.Fab")
		)
		(fp_line
			(start -0.4953 1.6002)
			(end 0.4953 1.6002)
			(stroke
				(width 0.1)
				(type default)
			)
			(layer "B.Fab")
		)
		(pad "1" smd rect
			(at 0 0 270)
			(size 0.762 0.889)
			(layers "B.Cu" "B.Mask" "B.Paste")
			(net "PVDDQ_KLM")
		)
		(pad "2" smd rect
			(at 0 1.397 270)
			(size 0.762 0.889)
			(layers "B.Cu" "B.Mask" "B.Paste")
			(net "GND")
		)
		(zone
			(layer "B.Cu")
			(hatch none 0.5)
			(connect_pads
				(clearance 0)
			)
			(min_thickness 0.25)
			(keepout
				(tracks not_allowed)
				(vias allowed)
				(pads allowed)
				(copperpour not_allowed)
				(footprints allowed)
			)
			(placement
				(enabled no)
				(sheetname "")
			)
			(fill
				(thermal_gap 0.5)
				(thermal_bridge_width 0.5)
				(island_removal_mode 0)
			)
			(polygon
				(pts
					(xy 88.8365 -149.4282) (xy 89.3445 -149.4282) (xy 89.3445 -150.1902) (xy 88.8365 -150.1902)
				)
			)
		)
	)
	(footprint ""
		(layer "B.Cu")
		(at 95.374968 -27.051 90)
		(property "Reference" "C8T3"
			(at -1.47828 0.78994 180)
			(unlocked yes)
			(layer "B.SilkS")
			(effects
				(font
					(size 0.4064 0.254)
					(thickness 0.1524)
				)
				(justify mirror)
			)
		)
		(property "Value" ""
			(at 0 0 90)
			(layer "B.Fab")
			(effects
				(font
					(size 1.27 1.27)
				)
				(justify mirror)
			)
		)
		(duplicate_pad_numbers_are_jumpers no)
		(fp_poly
			(pts
				(xy 0.7239 -0.2159) (xy -0.7239 -0.2159) (xy -0.7239 1.9939) (xy 0.7239 1.9939)
			)
			(stroke
				(width 0)
				(type default)
			)
			(fill no)
			(layer "B.CrtYd")
		)
		(fp_line
			(start 0.7239 -0.2159)
			(end 0.7239 1.9939)
			(stroke
				(width 0.1)
				(type default)
			)
			(layer "B.Fab")
		)
		(fp_line
			(start -0.7239 -0.2159)
			(end 0.7239 -0.2159)
			(stroke
				(width 0.1)
				(type default)
			)
			(layer "B.Fab")
		)
		(fp_line
			(start 0.7239 1.9939)
			(end -0.7239 1.9939)
			(stroke
				(width 0.1)
				(type default)
			)
			(layer "B.Fab")
		)
		(fp_line
			(start -0.7239 1.9939)
			(end -0.7239 -0.2159)
			(stroke
				(width 0.1)
				(type default)
			)
			(layer "B.Fab")
		)
		(pad "1" smd rect
			(at 0 0 270)
			(size 1.27 1.016)
			(layers "B.Cu" "B.Mask" "B.Paste")
			(net "PVTT_GHJ")
		)
		(pad "2" smd rect
			(at 0 1.778 270)
			(size 1.27 1.016)
			(layers "B.Cu" "B.Mask" "B.Paste")
			(net "GND")
		)
		(zone
			(layer "B.Cu")
			(hatch none 0.5)
			(connect_pads
				(clearance 0)
			)
			(min_thickness 0.25)
			(keepout
				(tracks not_allowed)
				(vias allowed)
				(pads allowed)
				(copperpour not_allowed)
				(footprints allowed)
			)
			(placement
				(enabled no)
				(sheetname "")
			)
			(fill
				(thermal_gap 0.5)
				(thermal_bridge_width 0.5)
				(island_removal_mode 0)
			)
			(polygon
				(pts
					(xy 95.882968 -27.686) (xy 95.882968 -26.416) (xy 96.644968 -26.416) (xy 96.644968 -27.686)
				)
			)
		)
	)
)
